# S9S_MB_2U (Grand Teton) — schematic netlist excerpt (pin names and nets, part order shuffled) for the footprints in the layout excerpt that follows; sources: Cadence DE-HDL packaged netlist, KiCad conversion of 03242023_DA0F0TMBIJ0_F0T_Motherboard_J_brd_V01_OCP.brd

R4797  Q_RES  10K 1% EMPTY  pkg 0402LF  page 306 : A = P3V3_AUX ; B = A_HSC_LOW_GATE
R3754  Q_RES  33.2 1% CHIP  pkg 0402LF  page 171 : A = SMB_INA230_2_3V3AUX_SCL_R ; B = SMB_INA230_2_3V3AUX_SCL_R1

(kicad_pcb
	(version 20260206)
	(generator "pcbnew")
	(generator_version "10.0")
	(general
		(thickness 1.6)
		(legacy_teardrops no)
	)
	(paper "A4")
	(title_block
		(title "03242023_DA0F0TMBIJ0_F0T_Motherboard_J_brd_V01_OCP.brd")
		(comment 1 "Grand Teton / footprints 2197-2198 of 6105")
	)
	(layers
		(0 "F.Cu" signal "TOP")
		(4 "In1.Cu" signal "GND")
		(6 "In2.Cu" signal "IN1")
		(8 "In3.Cu" signal "GND1")
		(10 "In4.Cu" signal "IN2")
		(12 "In5.Cu" signal "GND2")
		(14 "In6.Cu" signal "IN3")
		(16 "In7.Cu" signal "GND3")
		(18 "In8.Cu" signal "VCC")
		(20 "In9.Cu" signal "VCC1")
		(22 "In10.Cu" signal "GND4")
		(24 "In11.Cu" signal "IN4")
		(26 "In12.Cu" signal "GND5")
		(28 "In13.Cu" signal "IN5")
		(30 "In14.Cu" signal "GND6")
		(32 "In15.Cu" signal "IN6")
		(34 "In16.Cu" signal "GND7")
		(2 "B.Cu" signal "BOTTOM")
		(9 "F.Adhes" user "F.Adhesive")
		(11 "B.Adhes" user "B.Adhesive")
		(13 "F.Paste" user "Package Geometry/Pastemask Top")
		(15 "B.Paste" user "Package Geometry/Pastemask Bottom")
		(5 "F.SilkS" user "Ref Des/Silkscreen Top")
		(7 "B.SilkS" user "Ref Des/Silkscreen Bottom")
		(1 "F.Mask" user "Board Geometry/Soldermask Top")
		(3 "B.Mask" user "Board Geometry/Soldermask Bottom")
		(17 "Dwgs.User" user "User.Drawings")
		(19 "Cmts.User" user "User.Comments")
		(21 "Eco1.User" user "User.Eco1")
		(23 "Eco2.User" user "User.Eco2")
		(25 "Edge.Cuts" user "Board Geometry/Outline")
		(27 "Margin" user)
		(31 "F.CrtYd" user "Package Geometry/Place Bound Top")
		(29 "B.CrtYd" user "Package Geometry/Place Bound Bottom")
		(35 "F.Fab" user "Ref Des/Assembly Top")
		(33 "B.Fab" user "Ref Des/Assembly Bottom")
	)
	(footprint ""
		(layer "F.Cu")
		(at 214.43188 -50.637948 90)
		(property "Reference" "R3754"
			(at 0 0 90)
			(layer "F.SilkS")
			(hide yes)
			(effects
				(font
					(size 1.27 1.27)
				)
			)
		)
		(property "Value" ""
			(at 0 0 90)
			(layer "F.Fab")
			(effects
				(font
					(size 1.27 1.27)
				)
			)
		)
		(duplicate_pad_numbers_are_jumpers no)
		(fp_line
			(start 0.7874 -0.4064)
			(end 0.7874 0.4064)
			(stroke
				(width 0.1524)
				(type default)
			)
			(layer "F.SilkS")
		)
		(fp_line
			(start -0.7874 -0.4064)
			(end 0.7874 -0.4064)
			(stroke
				(width 0.1524)
				(type default)
			)
			(layer "F.SilkS")
		)
		(fp_line
			(start 0.7874 0.4064)
			(end -0.7874 0.4064)
			(stroke
				(width 0.1524)
				(type default)
			)
			(layer "F.SilkS")
		)
		(fp_line
			(start -0.7874 0.4064)
			(end -0.7874 -0.4064)
			(stroke
				(width 0.1524)
				(type default)
			)
			(layer "F.SilkS")
		)
		(fp_line
			(start -0.12065 -0.305054)
			(end -0.12065 -0.2794)
			(stroke
				(width 0.1)
				(type default)
			)
			(layer "F.Fab")
		)
		(fp_line
			(start -0.67945 -0.305054)
			(end -0.12065 -0.305054)
			(stroke
				(width 0.1)
				(type default)
			)
			(layer "F.Fab")
		)
		(fp_line
			(start 0.67945 -0.3048)
			(end 0.67945 0.3048)
			(stroke
				(width 0.1)
				(type default)
			)
			(layer "F.Fab")
		)
		(fp_line
			(start 0.12065 -0.3048)
			(end 0.67945 -0.3048)
			(stroke
				(width 0.1)
				(type default)
			)
			(layer "F.Fab")
		)
		(fp_line
			(start 0.12065 -0.2794)
			(end 0.12065 -0.3048)
			(stroke
				(width 0.1)
				(type default)
			)
			(layer "F.Fab")
		)
		(fp_line
			(start -0.12065 -0.2794)
			(end 0.12065 -0.2794)
			(stroke
				(width 0.1)
				(type default)
			)
			(layer "F.Fab")
		)
		(fp_line
			(start 0.120396 0.2794)
			(end -0.12065 0.2794)
			(stroke
				(width 0.1)
				(type default)
			)
			(layer "F.Fab")
		)
		(fp_line
			(start -0.12065 0.2794)
			(end -0.12065 0.3048)
			(stroke
				(width 0.1)
				(type default)
			)
			(layer "F.Fab")
		)
		(fp_line
			(start 0.67945 0.3048)
			(end 0.120396 0.3048)
			(stroke
				(width 0.1)
				(type default)
			)
			(layer "F.Fab")
		)
		(fp_line
			(start 0.120396 0.3048)
			(end 0.120396 0.2794)
			(stroke
				(width 0.1)
				(type default)
			)
			(layer "F.Fab")
		)
		(fp_line
			(start -0.12065 0.3048)
			(end -0.67945 0.3048)
			(stroke
				(width 0.1)
				(type default)
			)
			(layer "F.Fab")
		)
		(fp_line
			(start -0.67945 0.3048)
			(end -0.67945 -0.305054)
			(stroke
				(width 0.1)
				(type default)
			)
			(layer "F.Fab")
		)
		(pad "1" smd circle
			(at -0.40005 0 90)
			(size 0 0)
			(layers "F.Cu" "F.Mask" "F.Paste")
			(net "SMB_INA230_2_3V3AUX_SCL_R")
		)
		(pad "2" smd circle
			(at 0.40005 0 90)
			(size 0 0)
			(layers "F.Cu" "F.Mask" "F.Paste")
			(net "SMB_INA230_2_3V3AUX_SCL_R1")
		)
	)
	(footprint ""
		(layer "F.Cu")
		(at 185.59272 -418.06876 90)
		(property "Reference" "R4797"
			(at 0 0 90)
			(layer "F.SilkS")
			(hide yes)
			(effects
				(font
					(size 1.27 1.27)
				)
			)
		)
		(property "Value" ""
			(at 0 0 90)
			(layer "F.Fab")
			(effects
				(font
					(size 1.27 1.27)
				)
			)
		)
		(duplicate_pad_numbers_are_jumpers no)
		(fp_line
			(start 0.7874 -0.4064)
			(end 0.7874 0.4064)
			(stroke
				(width 0.1524)
				(type default)
			)
			(layer "F.SilkS")
		)
		(fp_line
			(start -0.7874 -0.4064)
			(end 0.7874 -0.4064)
			(stroke
				(width 0.1524)
				(type default)
			)
			(layer "F.SilkS")
		)
		(fp_line
			(start 0.7874 0.4064)
			(end -0.7874 0.4064)
			(stroke
				(width 0.1524)
				(type default)
			)
			(layer "F.SilkS")
		)
		(fp_line
			(start -0.7874 0.4064)
			(end -0.7874 -0.4064)
			(stroke
				(width 0.1524)
				(type default)
			)
			(layer "F.SilkS")
		)
		(fp_line
			(start -0.12065 -0.305054)
			(end -0.12065 -0.2794)
			(stroke
				(width 0.1)
				(type default)
			)
			(layer "F.Fab")
		)
		(fp_line
			(start -0.67945 -0.305054)
			(end -0.12065 -0.305054)
			(stroke
				(width 0.1)
				(type default)
			)
			(layer "F.Fab")
		)
		(fp_line
			(start 0.67945 -0.3048)
			(end 0.67945 0.3048)
			(stroke
				(width 0.1)
				(type default)
			)
			(layer "F.Fab")
		)
		(fp_line
			(start 0.12065 -0.3048)
			(end 0.67945 -0.3048)
			(stroke
				(width 0.1)
				(type default)
			)
			(layer "F.Fab")
		)
		(fp_line
			(start 0.12065 -0.2794)
			(end 0.12065 -0.3048)
			(stroke
				(width 0.1)
				(type default)
			)
			(layer "F.Fab")
		)
		(fp_line
			(start -0.12065 -0.2794)
			(end 0.12065 -0.2794)
			(stroke
				(width 0.1)
				(type default)
			)
			(layer "F.Fab")
		)
		(fp_line
			(start 0.120396 0.2794)
			(end -0.12065 0.2794)
			(stroke
				(width 0.1)
				(type default)
			)
			(layer "F.Fab")
		)
		(fp_line
			(start -0.12065 0.2794)
			(end -0.12065 0.3048)
			(stroke
				(width 0.1)
				(type default)
			)
			(layer "F.Fab")
		)
		(fp_line
			(start 0.67945 0.3048)
			(end 0.120396 0.3048)
			(stroke
				(width 0.1)
				(type default)
			)
			(layer "F.Fab")
		)
		(fp_line
			(start 0.120396 0.3048)
			(end 0.120396 0.2794)
			(stroke
				(width 0.1)
				(type default)
			)
			(layer "F.Fab")
		)
		(fp_line
			(start -0.12065 0.3048)
			(end -0.67945 0.3048)
			(stroke
				(width 0.1)
				(type default)
			)
			(layer "F.Fab")
		)
		(fp_line
			(start -0.67945 0.3048)
			(end -0.67945 -0.305054)
			(stroke
				(width 0.1)
				(type default)
			)
			(layer "F.Fab")
		)
		(pad "1" smd circle
			(at -0.40005 0 90)
			(size 0 0)
			(layers "F.Cu" "F.Mask" "F.Paste")
			(net "P3V3_AUX")
		)
		(pad "2" smd circle
			(at 0.40005 0 90)
			(size 0 0)
			(layers "F.Cu" "F.Mask" "F.Paste")
			(net "A_HSC_LOW_GATE")
		)
	)
)
